(kicad_pcb
	(version 20260206)
	(generator "pcbnew")
	(generator_version "10.0")
	(general
		(thickness 1.6)
		(legacy_teardrops no)
	)
	(paper "A4")
	(title_block
		(title "Wiwynn_Tioga_Pass_MB.brd")
		(comment 1 "Tioga Pass / footprints 4552-4558 of 4770")
	)
	(layers
		(0 "F.Cu" signal "TOP")
		(4 "In1.Cu" signal "L2GND")
		(6 "In2.Cu" signal "L3")
		(8 "In3.Cu" signal "L4GND")
		(10 "In4.Cu" signal "L5")
		(12 "In5.Cu" signal "L6GND")
		(14 "In6.Cu" signal "L7VCC")
		(16 "In7.Cu" signal "L8VCC")
		(18 "In8.Cu" signal "L9GND")
		(20 "In9.Cu" signal "L10")
		(22 "In10.Cu" signal "L11GND")
		(24 "In11.Cu" signal "L12")
		(26 "In12.Cu" signal "L13GND")
		(2 "B.Cu" signal "BOTTOM")
		(9 "F.Adhes" user "F.Adhesive")
		(11 "B.Adhes" user "B.Adhesive")
		(13 "F.Paste" user "Package Geometry/Pastemask Top")
		(15 "B.Paste" user "Package Geometry/Pastemask Bottom")
		(5 "F.SilkS" user "Ref Des/Silkscreen Top")
		(7 "B.SilkS" user "Ref Des/Silkscreen Bottom")
		(1 "F.Mask" user "Board Geometry/Soldermask Top")
		(3 "B.Mask" user "Board Geometry/Soldermask Bottom")
		(17 "Dwgs.User" user "User.Drawings")
		(19 "Cmts.User" user "User.Comments")
		(21 "Eco1.User" user "User.Eco1")
		(23 "Eco2.User" user "User.Eco2")
		(25 "Edge.Cuts" user "Board Geometry/Outline")
		(27 "Margin" user)
		(31 "F.CrtYd" user "Package Geometry/Place Bound Top")
		(29 "B.CrtYd" user "Package Geometry/Place Bound Bottom")
		(35 "F.Fab" user "Ref Des/Assembly Top")
		(33 "B.Fab" user "Ref Des/Assembly Bottom")
	)
	(footprint ""
		(layer "B.Cu")
		(at 338.934806 -60.368434)
		(property "Reference" "R2U18"
			(at 0 0 0)
			(layer "B.SilkS")
			(hide yes)
			(effects
				(font
					(size 1.27 1.27)
				)
				(justify mirror)
			)
		)
		(property "Value" ""
			(at 0 0 0)
			(layer "B.Fab")
			(effects
				(font
					(size 1.27 1.27)
				)
				(justify mirror)
			)
		)
		(duplicate_pad_numbers_are_jumpers no)
		(fp_poly
			(pts
				(xy 0.2794 -0.1016) (xy -0.2794 -0.1016) (xy -0.2794 0.9906) (xy 0.2794 0.9906)
			)
			(stroke
				(width 0)
				(type default)
			)
			(fill no)
			(layer "B.CrtYd")
		)
		(fp_line
			(start -0.2794 -0.1016)
			(end 0.2794 -0.1016)
			(stroke
				(width 0.1)
				(type default)
			)
			(layer "B.Fab")
		)
		(fp_line
			(start -0.2794 0.9906)
			(end -0.2794 -0.1016)
			(stroke
				(width 0.1)
				(type default)
			)
			(layer "B.Fab")
		)
		(fp_line
			(start 0.2794 -0.1016)
			(end 0.2794 0.9906)
			(stroke
				(width 0.1)
				(type default)
			)
			(layer "B.Fab")
		)
		(fp_line
			(start 0.2794 0.9906)
			(end -0.2794 0.9906)
			(stroke
				(width 0.1)
				(type default)
			)
			(layer "B.Fab")
		)
		(pad "1" smd rect
			(at 0 0 180)
			(size 0.508 0.508)
			(layers "B.Cu" "B.Mask" "B.Paste")
			(net "P3E_CPU0_PE1_SS_RXP<2>")
		)
		(pad "2" smd rect
			(at 0 0.889 180)
			(size 0.508 0.508)
			(layers "B.Cu" "B.Mask" "B.Paste")
			(net "P3E_CPU0_PE1_SS_R_RXP<2>")
		)
		(zone
			(layer "B.Cu")
			(hatch none 0.5)
			(connect_pads
				(clearance 0)
			)
			(min_thickness 0.25)
			(keepout
				(tracks allowed)
				(vias not_allowed)
				(pads allowed)
				(copperpour not_allowed)
				(footprints allowed)
			)
			(placement
				(enabled no)
				(sheetname "")
			)
			(fill
				(thermal_gap 0.5)
				(thermal_bridge_width 0.5)
				(island_removal_mode 0)
			)
			(polygon
				(pts
					(xy 339.188806 -60.114434) (xy 338.680806 -60.114434) (xy 338.680806 -59.733434) (xy 339.188806 -59.733434)
				)
			)
		)
		(zone
			(layer "B.Cu")
			(hatch none 0.5)
			(connect_pads
				(clearance 0)
			)
			(min_thickness 0.25)
			(keepout
				(tracks not_allowed)
				(vias allowed)
				(pads allowed)
				(copperpour not_allowed)
				(footprints allowed)
			)
			(placement
				(enabled no)
				(sheetname "")
			)
			(fill
				(thermal_gap 0.5)
				(thermal_bridge_width 0.5)
				(island_removal_mode 0)
			)
			(polygon
				(pts
					(xy 339.188806 -59.733434) (xy 338.680806 -59.733434) (xy 338.680806 -60.114434) (xy 339.188806 -60.114434)
				)
			)
		)
	)
	(footprint ""
		(layer "B.Cu")
		(at 383.73685 -106.25455)
		(property "Reference" "C3N19"
			(at 0 0 0)
			(layer "B.SilkS")
			(hide yes)
			(effects
				(font
					(size 1.27 1.27)
				)
				(justify mirror)
			)
		)
		(property "Value" ""
			(at 0 0 0)
			(layer "B.Fab")
			(effects
				(font
					(size 1.27 1.27)
				)
				(justify mirror)
			)
		)
		(duplicate_pad_numbers_are_jumpers no)
		(fp_rect
			(start 0.2794 0.9144)
			(end -0.2794 -0.1143)
			(stroke
				(width 0)
				(type default)
			)
			(fill no)
			(layer "B.CrtYd")
		)
		(fp_line
			(start -0.2794 -0.1143)
			(end -0.2794 0.9144)
			(stroke
				(width 0.1)
				(type default)
			)
			(layer "B.Fab")
		)
		(fp_line
			(start -0.2794 0.9144)
			(end 0.2794 0.9144)
			(stroke
				(width 0.1)
				(type default)
			)
			(layer "B.Fab")
		)
		(fp_line
			(start 0.2794 -0.1143)
			(end -0.2794 -0.1143)
			(stroke
				(width 0.1)
				(type default)
			)
			(layer "B.Fab")
		)
		(fp_line
			(start 0.2794 0.9144)
			(end 0.2794 -0.1143)
			(stroke
				(width 0.1)
				(type default)
			)
			(layer "B.Fab")
		)
		(pad "1" smd custom
			(at 0 0 270)
			(size 0.10414 0.10414)
			(layers "B.Cu" "B.Mask" "B.Paste")
			(net "PVNN_PCH_STBY")
			(options
				(clearance outline)
				(anchor circle)
			)
			(primitives
				(gr_poly
					(pts
						(xy -0.20828 -0.08636) (xy -0.20828 0.08636) (xy -0.08636 0.20828) (xy 0.086614 0.20828) (xy 0.20828 0.086614)
						(xy 0.20828 -0.08636) (xy 0.08636 -0.20828) (xy -0.08636 -0.20828)
					)
					(width 0)
					(fill yes)
				)
			)
		)
		(pad "2" smd custom
			(at 0 0.8001 270)
			(size 0.10414 0.10414)
			(layers "B.Cu" "B.Mask" "B.Paste")
			(net "GND")
			(options
				(clearance outline)
				(anchor circle)
			)
			(primitives
				(gr_poly
					(pts
						(xy -0.20828 -0.08636) (xy -0.20828 0.08636) (xy -0.08636 0.20828) (xy 0.086614 0.20828) (xy 0.20828 0.086614)
						(xy 0.20828 -0.08636) (xy 0.08636 -0.20828) (xy -0.08636 -0.20828)
					)
					(width 0)
					(fill yes)
				)
			)
		)
		(zone
			(layer "B.Cu")
			(hatch none 0.5)
			(connect_pads
				(clearance 0)
			)
			(min_thickness 0.25)
			(keepout
				(tracks allowed)
				(vias not_allowed)
				(pads allowed)
				(copperpour not_allowed)
				(footprints allowed)
			)
			(placement
				(enabled no)
				(sheetname "")
			)
			(fill
				(thermal_gap 0.5)
				(thermal_bridge_width 0.5)
				(island_removal_mode 0)
			)
			(polygon
				(pts
					(xy 383.82448 -106.045) (xy 383.82448 -105.664) (xy 383.64922 -105.664) (xy 383.648966 -106.045)
				)
			)
		)
		(zone
			(layer "B.Cu")
			(hatch none 0.5)
			(connect_pads
				(clearance 0)
			)
			(min_thickness 0.25)
			(keepout
				(tracks not_allowed)
				(vias allowed)
				(pads allowed)
				(copperpour not_allowed)
				(footprints allowed)
			)
			(placement
				(enabled no)
				(sheetname "")
			)
			(fill
				(thermal_gap 0.5)
				(thermal_bridge_width 0.5)
				(island_removal_mode 0)
			)
			(polygon
				(pts
					(xy 383.82448 -106.045) (xy 383.82448 -105.664) (xy 383.64922 -105.664) (xy 383.648966 -106.045)
				)
			)
		)
	)
	(footprint ""
		(layer "B.Cu")
		(at 326.3519 -124.1298 -90)
		(property "Reference" "C7E1"
			(at 0 0 90)
			(layer "B.SilkS")
			(hide yes)
			(effects
				(font
					(size 1.27 1.27)
				)
				(justify mirror)
			)
		)
		(property "Value" ""
			(at 0 0 90)
			(layer "B.Fab")
			(effects
				(font
					(size 1.27 1.27)
				)
				(justify mirror)
			)
		)
		(duplicate_pad_numbers_are_jumpers no)
		(fp_poly
			(pts
				(xy -0.3048 -0.1016) (xy -0.3048 0.9906) (xy 0.3048 0.9906) (xy 0.3048 -0.1016)
			)
			(stroke
				(width 0)
				(type default)
			)
			(fill no)
			(layer "B.CrtYd")
		)
		(fp_line
			(start -0.3048 0.9906)
			(end -0.3048 -0.1016)
			(stroke
				(width 0.1)
				(type default)
			)
			(layer "B.Fab")
		)
		(fp_line
			(start 0.3048 0.9906)
			(end -0.3048 0.9906)
			(stroke
				(width 0.1)
				(type default)
			)
			(layer "B.Fab")
		)
		(fp_line
			(start -0.3048 -0.1016)
			(end 0.3048 -0.1016)
			(stroke
				(width 0.1)
				(type default)
			)
			(layer "B.Fab")
		)
		(fp_line
			(start 0.3048 -0.1016)
			(end 0.3048 0.9906)
			(stroke
				(width 0.1)
				(type default)
			)
			(layer "B.Fab")
		)
		(pad "1" smd rect
			(at 0 0 90)
			(size 0.508 0.508)
			(layers "B.Cu" "B.Mask" "B.Paste")
			(net "PVCCIO_CPU0")
		)
		(pad "2" smd rect
			(at 0 0.889 90)
			(size 0.508 0.508)
			(layers "B.Cu" "B.Mask" "B.Paste")
			(net "GND")
		)
		(zone
			(layer "B.Cu")
			(hatch none 0.5)
			(connect_pads
				(clearance 0)
			)
			(min_thickness 0.25)
			(keepout
				(tracks not_allowed)
				(vias allowed)
				(pads allowed)
				(copperpour not_allowed)
				(footprints allowed)
			)
			(placement
				(enabled no)
				(sheetname "")
			)
			(fill
				(thermal_gap 0.5)
				(thermal_bridge_width 0.5)
				(island_removal_mode 0)
			)
			(polygon
				(pts
					(xy 325.7169 -123.8758) (xy 325.7169 -124.3838) (xy 326.0979 -124.3838) (xy 326.0979 -123.8758)
				)
			)
		)
		(zone
			(layer "B.Cu")
			(hatch none 0.5)
			(connect_pads
				(clearance 0)
			)
			(min_thickness 0.25)
			(keepout
				(tracks allowed)
				(vias not_allowed)
				(pads allowed)
				(copperpour not_allowed)
				(footprints allowed)
			)
			(placement
				(enabled no)
				(sheetname "")
			)
			(fill
				(thermal_gap 0.5)
				(thermal_bridge_width 0.5)
				(island_removal_mode 0)
			)
			(polygon
				(pts
					(xy 326.0979 -123.8758) (xy 326.0979 -124.3838) (xy 325.7169 -124.3838) (xy 325.7169 -123.8758)
				)
			)
		)
	)
	(footprint ""
		(layer "B.Cu")
		(at 388.366 -87.3125 180)
		(property "Reference" "R8D11"
			(at 0.8382 -0.67818 180)
			(unlocked yes)
			(layer "B.SilkS")
			(effects
				(font
					(size 0.4064 0.254)
					(thickness 0.1524)
				)
				(justify left mirror)
			)
		)
		(property "Value" ""
			(at 0 0 0)
			(layer "B.Fab")
			(effects
				(font
					(size 1.27 1.27)
				)
				(justify mirror)
			)
		)
		(duplicate_pad_numbers_are_jumpers no)
		(fp_poly
			(pts
				(xy 0.2794 -0.1016) (xy -0.2794 -0.1016) (xy -0.2794 0.9906) (xy 0.2794 0.9906)
			)
			(stroke
				(width 0)
				(type default)
			)
			(fill no)
			(layer "B.CrtYd")
		)
		(fp_line
			(start 0.2794 0.9906)
			(end -0.2794 0.9906)
			(stroke
				(width 0.1)
				(type default)
			)
			(layer "B.Fab")
		)
		(fp_line
			(start 0.2794 -0.1016)
			(end 0.2794 0.9906)
			(stroke
				(width 0.1)
				(type default)
			)
			(layer "B.Fab")
		)
		(fp_line
			(start -0.2794 0.9906)
			(end -0.2794 -0.1016)
			(stroke
				(width 0.1)
				(type default)
			)
			(layer "B.Fab")
		)
		(fp_line
			(start -0.2794 -0.1016)
			(end 0.2794 -0.1016)
			(stroke
				(width 0.1)
				(type default)
			)
			(layer "B.Fab")
		)
		(pad "1" smd rect
			(at 0 0)
			(size 0.508 0.508)
			(layers "B.Cu" "B.Mask" "B.Paste")
			(net "RMII_PCH_SPRNGVLLE_ARB_OUT")
		)
		(pad "2" smd rect
			(at 0 0.889)
			(size 0.508 0.508)
			(layers "B.Cu" "B.Mask" "B.Paste")
			(net "RMII_PCH_SPRNGVLLE_ARB_OUT_R")
		)
		(zone
			(layer "B.Cu")
			(hatch none 0.5)
			(connect_pads
				(clearance 0)
			)
			(min_thickness 0.25)
			(keepout
				(tracks not_allowed)
				(vias allowed)
				(pads allowed)
				(copperpour not_allowed)
				(footprints allowed)
			)
			(placement
				(enabled no)
				(sheetname "")
			)
			(fill
				(thermal_gap 0.5)
				(thermal_bridge_width 0.5)
				(island_removal_mode 0)
			)
			(polygon
				(pts
					(xy 388.112 -87.9475) (xy 388.62 -87.9475) (xy 388.62 -87.5665) (xy 388.112 -87.5665)
				)
			)
		)
		(zone
			(layer "B.Cu")
			(hatch none 0.5)
			(connect_pads
				(clearance 0)
			)
			(min_thickness 0.25)
			(keepout
				(tracks allowed)
				(vias not_allowed)
				(pads allowed)
				(copperpour not_allowed)
				(footprints allowed)
			)
			(placement
				(enabled no)
				(sheetname "")
			)
			(fill
				(thermal_gap 0.5)
				(thermal_bridge_width 0.5)
				(island_removal_mode 0)
			)
			(polygon
				(pts
					(xy 388.112 -87.5665) (xy 388.62 -87.5665) (xy 388.62 -87.9475) (xy 388.112 -87.9475)
				)
			)
		)
	)
	(footprint ""
		(layer "B.Cu")
		(at 495.28476 -124.0663 180)
		(property "Reference" "R1M11"
			(at 0 0 0)
			(layer "B.SilkS")
			(hide yes)
			(effects
				(font
					(size 1.27 1.27)
				)
				(justify mirror)
			)
		)
		(property "Value" ""
			(at 0 0 0)
			(layer "B.Fab")
			(effects
				(font
					(size 1.27 1.27)
				)
				(justify mirror)
			)
		)
		(duplicate_pad_numbers_are_jumpers no)
		(fp_poly
			(pts
				(xy 0.2794 -0.1016) (xy -0.2794 -0.1016) (xy -0.2794 0.9906) (xy 0.2794 0.9906)
			)
			(stroke
				(width 0)
				(type default)
			)
			(fill no)
			(layer "B.CrtYd")
		)
		(fp_line
			(start 0.2794 0.9906)
			(end -0.2794 0.9906)
			(stroke
				(width 0.1)
				(type default)
			)
			(layer "B.Fab")
		)
		(fp_line
			(start 0.2794 -0.1016)
			(end 0.2794 0.9906)
			(stroke
				(width 0.1)
				(type default)
			)
			(layer "B.Fab")
		)
		(fp_line
			(start -0.2794 0.9906)
			(end -0.2794 -0.1016)
			(stroke
				(width 0.1)
				(type default)
			)
			(layer "B.Fab")
		)
		(fp_line
			(start -0.2794 -0.1016)
			(end 0.2794 -0.1016)
			(stroke
				(width 0.1)
				(type default)
			)
			(layer "B.Fab")
		)
		(pad "1" smd rect
			(at 0 0)
			(size 0.508 0.508)
			(layers "B.Cu" "B.Mask" "B.Paste")
			(net "P3V3")
		)
		(pad "2" smd rect
			(at 0 0.889)
			(size 0.508 0.508)
			(layers "B.Cu" "B.Mask" "B.Paste")
			(net "LED_SATA_ACT_R_N")
		)
		(zone
			(layer "B.Cu")
			(hatch none 0.5)
			(connect_pads
				(clearance 0)
			)
			(min_thickness 0.25)
			(keepout
				(tracks not_allowed)
				(vias allowed)
				(pads allowed)
				(copperpour not_allowed)
				(footprints allowed)
			)
			(placement
				(enabled no)
				(sheetname "")
			)
			(fill
				(thermal_gap 0.5)
				(thermal_bridge_width 0.5)
				(island_removal_mode 0)
			)
			(polygon
				(pts
					(xy 495.03076 -124.7013) (xy 495.53876 -124.7013) (xy 495.53876 -124.3203) (xy 495.03076 -124.3203)
				)
			)
		)
		(zone
			(layer "B.Cu")
			(hatch none 0.5)
			(connect_pads
				(clearance 0)
			)
			(min_thickness 0.25)
			(keepout
				(tracks allowed)
				(vias not_allowed)
				(pads allowed)
				(copperpour not_allowed)
				(footprints allowed)
			)
			(placement
				(enabled no)
				(sheetname "")
			)
			(fill
				(thermal_gap 0.5)
				(thermal_bridge_width 0.5)
				(island_removal_mode 0)
			)
			(polygon
				(pts
					(xy 495.03076 -124.3203) (xy 495.53876 -124.3203) (xy 495.53876 -124.7013) (xy 495.03076 -124.7013)
				)
			)
		)
	)
	(footprint ""
		(layer "B.Cu")
		(at 412.329884 -47.822104 -90)
		(property "Reference" "R8F38"
			(at 0 0 90)
			(layer "B.SilkS")
			(hide yes)
			(effects
				(font
					(size 1.27 1.27)
				)
				(justify mirror)
			)
		)
		(property "Value" ""
			(at 0 0 90)
			(layer "B.Fab")
			(effects
				(font
					(size 1.27 1.27)
				)
				(justify mirror)
			)
		)
		(duplicate_pad_numbers_are_jumpers no)
		(fp_poly
			(pts
				(xy 0.2794 -0.1016) (xy -0.2794 -0.1016) (xy -0.2794 0.9906) (xy 0.2794 0.9906)
			)
			(stroke
				(width 0)
				(type default)
			)
			(fill no)
			(layer "B.CrtYd")
		)
		(fp_line
			(start -0.2794 0.9906)
			(end -0.2794 -0.1016)
			(stroke
				(width 0.1)
				(type default)
			)
			(layer "B.Fab")
		)
		(fp_line
			(start 0.2794 0.9906)
			(end -0.2794 0.9906)
			(stroke
				(width 0.1)
				(type default)
			)
			(layer "B.Fab")
		)
		(fp_line
			(start -0.2794 -0.1016)
			(end 0.2794 -0.1016)
			(stroke
				(width 0.1)
				(type default)
			)
			(layer "B.Fab")
		)
		(fp_line
			(start 0.2794 -0.1016)
			(end 0.2794 0.9906)
			(stroke
				(width 0.1)
				(type default)
			)
			(layer "B.Fab")
		)
		(pad "1" smd rect
			(at 0 0 90)
			(size 0.508 0.508)
			(layers "B.Cu" "B.Mask" "B.Paste")
			(net "FM_CPU_ERR0_LVT3_N")
		)
		(pad "2" smd rect
			(at 0 0.889 90)
			(size 0.508 0.508)
			(layers "B.Cu" "B.Mask" "B.Paste")
			(net "FM_CPU_ERR0_LVT3_BMC_N")
		)
		(zone
			(layer "B.Cu")
			(hatch none 0.5)
			(connect_pads
				(clearance 0)
			)
			(min_thickness 0.25)
			(keepout
				(tracks not_allowed)
				(vias allowed)
				(pads allowed)
				(copperpour not_allowed)
				(footprints allowed)
			)
			(placement
				(enabled no)
				(sheetname "")
			)
			(fill
				(thermal_gap 0.5)
				(thermal_bridge_width 0.5)
				(island_removal_mode 0)
			)
			(polygon
				(pts
					(xy 411.694884 -47.568104) (xy 411.694884 -48.076104) (xy 412.075884 -48.076104) (xy 412.075884 -47.568104)
				)
			)
		)
		(zone
			(layer "B.Cu")
			(hatch none 0.5)
			(connect_pads
				(clearance 0)
			)
			(min_thickness 0.25)
			(keepout
				(tracks allowed)
				(vias not_allowed)
				(pads allowed)
				(copperpour not_allowed)
				(footprints allowed)
			)
			(placement
				(enabled no)
				(sheetname "")
			)
			(fill
				(thermal_gap 0.5)
				(thermal_bridge_width 0.5)
				(island_removal_mode 0)
			)
			(polygon
				(pts
					(xy 412.075884 -47.568104) (xy 412.075884 -48.076104) (xy 411.694884 -48.076104) (xy 411.694884 -47.568104)
				)
			)
		)
	)
	(footprint ""
		(layer "B.Cu")
		(at 106.223054 -85.06714)
		(property "Reference" "C8P3"
			(at 0 0 0)
			(layer "B.SilkS")
			(hide yes)
			(effects
				(font
					(size 1.27 1.27)
				)
				(justify mirror)
			)
		)
		(property "Value" ""
			(at 0 0 0)
			(layer "B.Fab")
			(effects
				(font
					(size 1.27 1.27)
				)
				(justify mirror)
			)
		)
		(duplicate_pad_numbers_are_jumpers no)
		(fp_poly
			(pts
				(xy 0.7239 -0.2159) (xy -0.7239 -0.2159) (xy -0.7239 1.9939) (xy 0.7239 1.9939)
			)
			(stroke
				(width 0)
				(type default)
			)
			(fill no)
			(layer "B.CrtYd")
		)
		(fp_line
			(start -0.7239 -0.2159)
			(end 0.7239 -0.2159)
			(stroke
				(width 0.1)
				(type default)
			)
			(layer "B.Fab")
		)
		(fp_line
			(start -0.7239 1.9939)
			(end -0.7239 -0.2159)
			(stroke
				(width 0.1)
				(type default)
			)
			(layer "B.Fab")
		)
		(fp_line
			(start 0.7239 -0.2159)
			(end 0.7239 1.9939)
			(stroke
				(width 0.1)
				(type default)
			)
			(layer "B.Fab")
		)
		(fp_line
			(start 0.7239 1.9939)
			(end -0.7239 1.9939)
			(stroke
				(width 0.1)
				(type default)
			)
			(layer "B.Fab")
		)
		(pad "1" smd rect
			(at 0 0 180)
			(size 1.27 1.016)
			(layers "B.Cu" "B.Mask" "B.Paste")
			(net "PVDDQ_KLM")
		)
		(pad "2" smd rect
			(at 0 1.778 180)
			(size 1.27 1.016)
			(layers "B.Cu" "B.Mask" "B.Paste")
			(net "GND")
		)
		(zone
			(layer "B.Cu")
			(hatch none 0.5)
			(connect_pads
				(clearance 0)
			)
			(min_thickness 0.25)
			(keepout
				(tracks not_allowed)
				(vias allowed)
				(pads allowed)
				(copperpour not_allowed)
				(footprints allowed)
			)
			(placement
				(enabled no)
				(sheetname "")
			)
			(fill
				(thermal_gap 0.5)
				(thermal_bridge_width 0.5)
				(island_removal_mode 0)
			)
			(polygon
				(pts
					(xy 106.858054 -84.55914) (xy 105.588054 -84.55914) (xy 105.588054 -83.79714) (xy 106.858054 -83.79714)
				)
			)
		)
	)
)
